(kicad_pcb
	(version 20260206)
	(generator "pcbnew")
	(generator_version "10.0")
	(general
		(thickness 1.6)
		(legacy_teardrops no)
	)
	(paper "A4")
	(title_block
		(title "04192023_DAF0TMB3IC0_F0TG_MB_C_brd_V02_OCP.brd")
		(comment 1 "Grand Teton / footprints 7915-7921 of 8354")
	)
	(layers
		(0 "F.Cu" signal "TOP")
		(4 "In1.Cu" signal "GND")
		(6 "In2.Cu" signal "IN1")
		(8 "In3.Cu" signal "GND1")
		(10 "In4.Cu" signal "IN2")
		(12 "In5.Cu" signal "GND2")
		(14 "In6.Cu" signal "IN3")
		(16 "In7.Cu" signal "GND3")
		(18 "In8.Cu" signal "VCC")
		(20 "In9.Cu" signal "VCC1")
		(22 "In10.Cu" signal "GND4")
		(24 "In11.Cu" signal "IN4")
		(26 "In12.Cu" signal "GND5")
		(28 "In13.Cu" signal "IN5")
		(30 "In14.Cu" signal "GND6")
		(32 "In15.Cu" signal "IN6")
		(34 "In16.Cu" signal "GND7")
		(2 "B.Cu" signal "BOTTOM")
		(9 "F.Adhes" user "F.Adhesive")
		(11 "B.Adhes" user "B.Adhesive")
		(13 "F.Paste" user "Package Geometry/Pastemask Top")
		(15 "B.Paste" user "Package Geometry/Pastemask Bottom")
		(5 "F.SilkS" user "Ref Des/Silkscreen Top")
		(7 "B.SilkS" user "Ref Des/Silkscreen Bottom")
		(1 "F.Mask" user "Board Geometry/Soldermask Top")
		(3 "B.Mask" user "Board Geometry/Soldermask Bottom")
		(17 "Dwgs.User" user "User.Drawings")
		(19 "Cmts.User" user "User.Comments")
		(21 "Eco1.User" user "User.Eco1")
		(23 "Eco2.User" user "User.Eco2")
		(25 "Edge.Cuts" user "Board Geometry/Outline")
		(27 "Margin" user)
		(31 "F.CrtYd" user "Package Geometry/Place Bound Top")
		(29 "B.CrtYd" user "Package Geometry/Place Bound Bottom")
		(35 "F.Fab" user "Ref Des/Assembly Top")
		(33 "B.Fab" user "Ref Des/Assembly Bottom")
	)
	(footprint ""
		(layer "B.Cu")
		(at 56.79313 -346.788994 90)
		(property "Reference" "PC444_1"
			(at 0 0 90)
			(layer "B.SilkS")
			(hide yes)
			(effects
				(font
					(size 1.27 1.27)
				)
				(justify mirror)
			)
		)
		(property "Value" ""
			(at 0 0 90)
			(layer "B.Fab")
			(effects
				(font
					(size 1.27 1.27)
				)
				(justify mirror)
			)
		)
		(duplicate_pad_numbers_are_jumpers no)
		(fp_line
			(start 1.524 -0.762)
			(end -1.524 -0.762)
			(stroke
				(width 0.1524)
				(type default)
			)
			(layer "B.SilkS")
		)
		(fp_line
			(start -1.524 -0.762)
			(end -1.524 0.762)
			(stroke
				(width 0.1524)
				(type default)
			)
			(layer "B.SilkS")
		)
		(fp_line
			(start 1.524 0.762)
			(end 1.524 -0.762)
			(stroke
				(width 0.1524)
				(type default)
			)
			(layer "B.SilkS")
		)
		(fp_line
			(start -1.524 0.762)
			(end 1.524 0.762)
			(stroke
				(width 0.1524)
				(type default)
			)
			(layer "B.SilkS")
		)
		(fp_line
			(start 1.1049 -0.724916)
			(end 1.1049 0.724916)
			(stroke
				(width 0.1)
				(type default)
			)
			(layer "B.Fab")
		)
		(fp_line
			(start -1.1049 -0.724916)
			(end 1.1049 -0.724916)
			(stroke
				(width 0.1)
				(type default)
			)
			(layer "B.Fab")
		)
		(fp_line
			(start 1.1049 0.724916)
			(end -1.1049 0.724916)
			(stroke
				(width 0.1)
				(type default)
			)
			(layer "B.Fab")
		)
		(fp_line
			(start -1.1049 0.724916)
			(end -1.1049 -0.724916)
			(stroke
				(width 0.1)
				(type default)
			)
			(layer "B.Fab")
		)
		(pad "1" smd rect
			(at 0.889 0 90)
			(size 1.016 1.27)
			(layers "B.Cu" "B.Mask" "B.Paste")
			(net "SW_P12V_AUX_PVDDIO_P1_FLT")
		)
		(pad "2" smd rect
			(at -0.889 0 90)
			(size 1.016 1.27)
			(layers "B.Cu" "B.Mask" "B.Paste")
			(net "GND")
		)
	)
	(footprint ""
		(layer "B.Cu")
		(at 168.783762 -383.304288 180)
		(property "Reference" "R6797"
			(at 0 0 0)
			(layer "B.SilkS")
			(hide yes)
			(effects
				(font
					(size 1.27 1.27)
				)
				(justify mirror)
			)
		)
		(property "Value" ""
			(at 0 0 0)
			(layer "B.Fab")
			(effects
				(font
					(size 1.27 1.27)
				)
				(justify mirror)
			)
		)
		(duplicate_pad_numbers_are_jumpers no)
		(fp_line
			(start 0.32512 0.175006)
			(end 0.32512 -0.175006)
			(stroke
				(width 0.1)
				(type default)
			)
			(layer "B.Fab")
		)
		(fp_line
			(start 0.32512 -0.175006)
			(end -0.32512 -0.175006)
			(stroke
				(width 0.1)
				(type default)
			)
			(layer "B.Fab")
		)
		(fp_line
			(start -0.32512 0.175006)
			(end 0.32512 0.175006)
			(stroke
				(width 0.1)
				(type default)
			)
			(layer "B.Fab")
		)
		(fp_line
			(start -0.32512 -0.175006)
			(end -0.32512 0.175006)
			(stroke
				(width 0.1)
				(type default)
			)
			(layer "B.Fab")
		)
		(pad "1" smd rect
			(at 0.2667 0)
			(size 0.3048 0.381)
			(layers "B.Cu" "B.Mask" "B.Paste")
			(net "NCF_CPU1_P2_GND")
		)
		(pad "2" smd rect
			(at -0.2667 0 180)
			(size 0.3048 0.381)
			(layers "B.Cu" "B.Mask" "B.Paste")
			(net "GND")
		)
	)
	(footprint ""
		(layer "B.Cu")
		(at 413.123634 -194.88531 180)
		(property "Reference" "R35"
			(at 0 0 0)
			(layer "B.SilkS")
			(hide yes)
			(effects
				(font
					(size 1.27 1.27)
				)
				(justify mirror)
			)
		)
		(property "Value" ""
			(at 0 0 0)
			(layer "B.Fab")
			(effects
				(font
					(size 1.27 1.27)
				)
				(justify mirror)
			)
		)
		(duplicate_pad_numbers_are_jumpers no)
		(fp_line
			(start 0.7874 0.4064)
			(end 0.7874 -0.4064)
			(stroke
				(width 0.1524)
				(type default)
			)
			(layer "B.SilkS")
		)
		(fp_line
			(start 0.7874 -0.4064)
			(end -0.7874 -0.4064)
			(stroke
				(width 0.1524)
				(type default)
			)
			(layer "B.SilkS")
		)
		(fp_line
			(start -0.7874 0.4064)
			(end 0.7874 0.4064)
			(stroke
				(width 0.1524)
				(type default)
			)
			(layer "B.SilkS")
		)
		(fp_line
			(start -0.7874 -0.4064)
			(end -0.7874 0.4064)
			(stroke
				(width 0.1524)
				(type default)
			)
			(layer "B.SilkS")
		)
		(fp_line
			(start 0.67945 0.3048)
			(end 0.67945 -0.305054)
			(stroke
				(width 0.1)
				(type default)
			)
			(layer "B.Fab")
		)
		(fp_line
			(start 0.67945 -0.305054)
			(end 0.12065 -0.305054)
			(stroke
				(width 0.1)
				(type default)
			)
			(layer "B.Fab")
		)
		(fp_line
			(start 0.12065 0.3048)
			(end 0.67945 0.3048)
			(stroke
				(width 0.1)
				(type default)
			)
			(layer "B.Fab")
		)
		(fp_line
			(start 0.12065 0.2794)
			(end 0.12065 0.3048)
			(stroke
				(width 0.1)
				(type default)
			)
			(layer "B.Fab")
		)
		(fp_line
			(start 0.12065 -0.2794)
			(end -0.12065 -0.2794)
			(stroke
				(width 0.1)
				(type default)
			)
			(layer "B.Fab")
		)
		(fp_line
			(start 0.12065 -0.305054)
			(end 0.12065 -0.2794)
			(stroke
				(width 0.1)
				(type default)
			)
			(layer "B.Fab")
		)
		(fp_line
			(start -0.120396 0.3048)
			(end -0.120396 0.2794)
			(stroke
				(width 0.1)
				(type default)
			)
			(layer "B.Fab")
		)
		(fp_line
			(start -0.120396 0.2794)
			(end 0.12065 0.2794)
			(stroke
				(width 0.1)
				(type default)
			)
			(layer "B.Fab")
		)
		(fp_line
			(start -0.12065 -0.2794)
			(end -0.12065 -0.3048)
			(stroke
				(width 0.1)
				(type default)
			)
			(layer "B.Fab")
		)
		(fp_line
			(start -0.12065 -0.3048)
			(end -0.67945 -0.3048)
			(stroke
				(width 0.1)
				(type default)
			)
			(layer "B.Fab")
		)
		(fp_line
			(start -0.67945 0.3048)
			(end -0.120396 0.3048)
			(stroke
				(width 0.1)
				(type default)
			)
			(layer "B.Fab")
		)
		(fp_line
			(start -0.67945 -0.3048)
			(end -0.67945 0.3048)
			(stroke
				(width 0.1)
				(type default)
			)
			(layer "B.Fab")
		)
		(pad "1" smd circle
			(at 0.40005 0)
			(size 0 0)
			(layers "B.Cu" "B.Mask" "B.Paste")
			(net "PD_CHG_CPU0_DIMM0_SAA")
		)
		(pad "2" smd circle
			(at -0.40005 0)
			(size 0 0)
			(layers "B.Cu" "B.Mask" "B.Paste")
			(net "GND")
		)
	)
	(footprint ""
		(layer "B.Cu")
		(at 312.144664 -73.534778)
		(property "Reference" "Q87"
			(at 1.157478 2.63525 0)
			(unlocked yes)
			(layer "B.SilkS")
			(effects
				(font
					(size 0.7874 0.5842)
					(thickness 0.1524)
				)
				(justify left mirror)
			)
		)
		(property "Value" ""
			(at 0 0 0)
			(layer "B.Fab")
			(effects
				(font
					(size 1.27 1.27)
				)
				(justify mirror)
			)
		)
		(duplicate_pad_numbers_are_jumpers no)
		(fp_line
			(start -1.332738 -1.100074)
			(end -1.332738 1.100074)
			(stroke
				(width 0.1524)
				(type default)
			)
			(layer "B.SilkS")
		)
		(fp_line
			(start -1.332738 1.100074)
			(end 1.332738 1.100074)
			(stroke
				(width 0.1524)
				(type default)
			)
			(layer "B.SilkS")
		)
		(fp_line
			(start -0.4826 -1.100074)
			(end -1.332738 -1.100074)
			(stroke
				(width 0.1524)
				(type default)
			)
			(layer "B.SilkS")
		)
		(fp_line
			(start 0 -0.541274)
			(end -0.4826 -1.100074)
			(stroke
				(width 0.1524)
				(type default)
			)
			(layer "B.SilkS")
		)
		(fp_line
			(start 0.4826 -1.100074)
			(end 0 -0.541274)
			(stroke
				(width 0.1524)
				(type default)
			)
			(layer "B.SilkS")
		)
		(fp_line
			(start 1.332738 -1.100074)
			(end 0.4826 -1.100074)
			(stroke
				(width 0.1524)
				(type default)
			)
			(layer "B.SilkS")
		)
		(fp_line
			(start 1.332738 1.100074)
			(end 1.332738 -1.100074)
			(stroke
				(width 0.1524)
				(type default)
			)
			(layer "B.SilkS")
		)
		(fp_poly
			(pts
				(xy 1.533144 -0.649986) (xy 2.2352 -1.001014) (xy 2.2352 -0.298958)
			)
			(stroke
				(width 0)
				(type default)
			)
			(fill yes)
			(layer "B.SilkS")
		)
		(fp_line
			(start -0.674878 -1.100074)
			(end -0.674878 1.100074)
			(stroke
				(width 0.1)
				(type default)
			)
			(layer "B.Fab")
		)
		(fp_line
			(start -0.674878 1.100074)
			(end 0.674878 1.100074)
			(stroke
				(width 0.1)
				(type default)
			)
			(layer "B.Fab")
		)
		(fp_line
			(start 0.674878 -1.100074)
			(end -0.674878 -1.100074)
			(stroke
				(width 0.1)
				(type default)
			)
			(layer "B.Fab")
		)
		(fp_line
			(start 0.674878 1.100074)
			(end 0.674878 -1.100074)
			(stroke
				(width 0.1)
				(type default)
			)
			(layer "B.Fab")
		)
		(fp_poly
			(pts
				(xy 2.2352 -0.298958) (xy 2.2352 -1.001014) (xy 1.533144 -0.649986)
			)
			(stroke
				(width 0)
				(type default)
			)
			(fill yes)
			(layer "B.Fab")
		)
		(pad "1" smd rect
			(at 0.94996 -0.649986 90)
			(size 0.4318 0.508)
			(layers "B.Cu" "B.Mask" "B.Paste")
			(net "GND")
		)
		(pad "2" smd rect
			(at 0.94996 0 90)
			(size 0.4318 0.508)
			(layers "B.Cu" "B.Mask" "B.Paste")
			(net "RST_CPU0_RSMRST_N")
		)
		(pad "3" smd rect
			(at 0.94996 0.649986 90)
			(size 0.4318 0.508)
			(layers "B.Cu" "B.Mask" "B.Paste")
			(net "LED_PWRGD_SYS_PWROK_R_D")
		)
		(pad "4" smd rect
			(at -0.94996 0.649986 90)
			(size 0.4318 0.508)
			(layers "B.Cu" "B.Mask" "B.Paste")
			(net "GND")
		)
		(pad "5" smd rect
			(at -0.94996 0 90)
			(size 0.4318 0.508)
			(layers "B.Cu" "B.Mask" "B.Paste")
			(net "SCM_SYS_PWROK_R2")
		)
		(pad "6" smd rect
			(at -0.94996 -0.649986 90)
			(size 0.4318 0.508)
			(layers "B.Cu" "B.Mask" "B.Paste")
			(net "LED_RST_RSMRST_PLD_R_N_D")
		)
	)
	(footprint ""
		(layer "B.Cu")
		(at 443.29985 -193.99631)
		(property "Reference" "R100"
			(at 0 0 0)
			(layer "B.SilkS")
			(hide yes)
			(effects
				(font
					(size 1.27 1.27)
				)
				(justify mirror)
			)
		)
		(property "Value" ""
			(at 0 0 0)
			(layer "B.Fab")
			(effects
				(font
					(size 1.27 1.27)
				)
				(justify mirror)
			)
		)
		(duplicate_pad_numbers_are_jumpers no)
		(fp_line
			(start -0.7874 -0.4064)
			(end -0.7874 0.4064)
			(stroke
				(width 0.1524)
				(type default)
			)
			(layer "B.SilkS")
		)
		(fp_line
			(start -0.7874 0.4064)
			(end 0.7874 0.4064)
			(stroke
				(width 0.1524)
				(type default)
			)
			(layer "B.SilkS")
		)
		(fp_line
			(start 0.7874 -0.4064)
			(end -0.7874 -0.4064)
			(stroke
				(width 0.1524)
				(type default)
			)
			(layer "B.SilkS")
		)
		(fp_line
			(start 0.7874 0.4064)
			(end 0.7874 -0.4064)
			(stroke
				(width 0.1524)
				(type default)
			)
			(layer "B.SilkS")
		)
		(fp_line
			(start -0.67945 -0.3048)
			(end -0.67945 0.3048)
			(stroke
				(width 0.1)
				(type default)
			)
			(layer "B.Fab")
		)
		(fp_line
			(start -0.67945 0.3048)
			(end -0.120396 0.3048)
			(stroke
				(width 0.1)
				(type default)
			)
			(layer "B.Fab")
		)
		(fp_line
			(start -0.12065 -0.3048)
			(end -0.67945 -0.3048)
			(stroke
				(width 0.1)
				(type default)
			)
			(layer "B.Fab")
		)
		(fp_line
			(start -0.12065 -0.2794)
			(end -0.12065 -0.3048)
			(stroke
				(width 0.1)
				(type default)
			)
			(layer "B.Fab")
		)
		(fp_line
			(start -0.120396 0.2794)
			(end 0.12065 0.2794)
			(stroke
				(width 0.1)
				(type default)
			)
			(layer "B.Fab")
		)
		(fp_line
			(start -0.120396 0.3048)
			(end -0.120396 0.2794)
			(stroke
				(width 0.1)
				(type default)
			)
			(layer "B.Fab")
		)
		(fp_line
			(start 0.12065 -0.305054)
			(end 0.12065 -0.2794)
			(stroke
				(width 0.1)
				(type default)
			)
			(layer "B.Fab")
		)
		(fp_line
			(start 0.12065 -0.2794)
			(end -0.12065 -0.2794)
			(stroke
				(width 0.1)
				(type default)
			)
			(layer "B.Fab")
		)
		(fp_line
			(start 0.12065 0.2794)
			(end 0.12065 0.3048)
			(stroke
				(width 0.1)
				(type default)
			)
			(layer "B.Fab")
		)
		(fp_line
			(start 0.12065 0.3048)
			(end 0.67945 0.3048)
			(stroke
				(width 0.1)
				(type default)
			)
			(layer "B.Fab")
		)
		(fp_line
			(start 0.67945 -0.305054)
			(end 0.12065 -0.305054)
			(stroke
				(width 0.1)
				(type default)
			)
			(layer "B.Fab")
		)
		(fp_line
			(start 0.67945 0.3048)
			(end 0.67945 -0.305054)
			(stroke
				(width 0.1)
				(type default)
			)
			(layer "B.Fab")
		)
		(pad "1" smd circle
			(at 0.40005 0 180)
			(size 0 0)
			(layers "B.Cu" "B.Mask" "B.Paste")
			(net "P3V3")
		)
		(pad "2" smd circle
			(at -0.40005 0 180)
			(size 0 0)
			(layers "B.Cu" "B.Mask" "B.Paste")
			(net "PWRGD_CHK_CPU0_DIMM")
		)
	)
	(footprint ""
		(layer "B.Cu")
		(at 103.125524 -414.329626 180)
		(property "Reference" "R1517"
			(at 0 0 0)
			(layer "B.SilkS")
			(hide yes)
			(effects
				(font
					(size 1.27 1.27)
				)
				(justify mirror)
			)
		)
		(property "Value" ""
			(at 0 0 0)
			(layer "B.Fab")
			(effects
				(font
					(size 1.27 1.27)
				)
				(justify mirror)
			)
		)
		(duplicate_pad_numbers_are_jumpers no)
		(fp_line
			(start 0.7874 0.4064)
			(end 0.7874 -0.4064)
			(stroke
				(width 0.1524)
				(type default)
			)
			(layer "B.SilkS")
		)
		(fp_line
			(start 0.7874 -0.4064)
			(end -0.7874 -0.4064)
			(stroke
				(width 0.1524)
				(type default)
			)
			(layer "B.SilkS")
		)
		(fp_line
			(start -0.7874 0.4064)
			(end 0.7874 0.4064)
			(stroke
				(width 0.1524)
				(type default)
			)
			(layer "B.SilkS")
		)
		(fp_line
			(start -0.7874 -0.4064)
			(end -0.7874 0.4064)
			(stroke
				(width 0.1524)
				(type default)
			)
			(layer "B.SilkS")
		)
		(fp_line
			(start 0.67945 0.3048)
			(end 0.67945 -0.305054)
			(stroke
				(width 0.1)
				(type default)
			)
			(layer "B.Fab")
		)
		(fp_line
			(start 0.67945 -0.305054)
			(end 0.12065 -0.305054)
			(stroke
				(width 0.1)
				(type default)
			)
			(layer "B.Fab")
		)
		(fp_line
			(start 0.12065 0.3048)
			(end 0.67945 0.3048)
			(stroke
				(width 0.1)
				(type default)
			)
			(layer "B.Fab")
		)
		(fp_line
			(start 0.12065 0.2794)
			(end 0.12065 0.3048)
			(stroke
				(width 0.1)
				(type default)
			)
			(layer "B.Fab")
		)
		(fp_line
			(start 0.12065 -0.2794)
			(end -0.12065 -0.2794)
			(stroke
				(width 0.1)
				(type default)
			)
			(layer "B.Fab")
		)
		(fp_line
			(start 0.12065 -0.305054)
			(end 0.12065 -0.2794)
			(stroke
				(width 0.1)
				(type default)
			)
			(layer "B.Fab")
		)
		(fp_line
			(start -0.120396 0.3048)
			(end -0.120396 0.2794)
			(stroke
				(width 0.1)
				(type default)
			)
			(layer "B.Fab")
		)
		(fp_line
			(start -0.120396 0.2794)
			(end 0.12065 0.2794)
			(stroke
				(width 0.1)
				(type default)
			)
			(layer "B.Fab")
		)
		(fp_line
			(start -0.12065 -0.2794)
			(end -0.12065 -0.3048)
			(stroke
				(width 0.1)
				(type default)
			)
			(layer "B.Fab")
		)
		(fp_line
			(start -0.12065 -0.3048)
			(end -0.67945 -0.3048)
			(stroke
				(width 0.1)
				(type default)
			)
			(layer "B.Fab")
		)
		(fp_line
			(start -0.67945 0.3048)
			(end -0.120396 0.3048)
			(stroke
				(width 0.1)
				(type default)
			)
			(layer "B.Fab")
		)
		(fp_line
			(start -0.67945 -0.3048)
			(end -0.67945 0.3048)
			(stroke
				(width 0.1)
				(type default)
			)
			(layer "B.Fab")
		)
		(pad "1" smd circle
			(at 0.40005 0)
			(size 0 0)
			(layers "B.Cu" "B.Mask" "B.Paste")
			(net "SMB_HOST_CLK_3V3AUX_SDA")
		)
		(pad "2" smd circle
			(at -0.40005 0)
			(size 0 0)
			(layers "B.Cu" "B.Mask" "B.Paste")
			(net "SMB_HOST_CLK_3V3AUX_SDA_R1")
		)
	)
	(footprint ""
		(layer "B.Cu")
		(at 43.265852 -386.72516 180)
		(property "Reference" "R716"
			(at 0 0 0)
			(layer "B.SilkS")
			(hide yes)
			(effects
				(font
					(size 1.27 1.27)
				)
				(justify mirror)
			)
		)
		(property "Value" ""
			(at 0 0 0)
			(layer "B.Fab")
			(effects
				(font
					(size 1.27 1.27)
				)
				(justify mirror)
			)
		)
		(duplicate_pad_numbers_are_jumpers no)
		(fp_line
			(start 0.32512 0.175006)
			(end 0.32512 -0.175006)
			(stroke
				(width 0.1)
				(type default)
			)
			(layer "B.Fab")
		)
		(fp_line
			(start 0.32512 -0.175006)
			(end -0.32512 -0.175006)
			(stroke
				(width 0.1)
				(type default)
			)
			(layer "B.Fab")
		)
		(fp_line
			(start -0.32512 0.175006)
			(end 0.32512 0.175006)
			(stroke
				(width 0.1)
				(type default)
			)
			(layer "B.Fab")
		)
		(fp_line
			(start -0.32512 -0.175006)
			(end -0.32512 0.175006)
			(stroke
				(width 0.1)
				(type default)
			)
			(layer "B.Fab")
		)
		(pad "1" smd rect
			(at 0.2667 0)
			(size 0.3048 0.381)
			(layers "B.Cu" "B.Mask" "B.Paste")
			(net "P1V8_CPU1_RT_1D")
		)
		(pad "2" smd rect
			(at -0.2667 0 180)
			(size 0.3048 0.381)
			(layers "B.Cu" "B.Mask" "B.Paste")
			(net "TEST0_RT_CPU1_P0")
		)
	)
)
